# S9S_MB_2U (Grand Teton) — schematic netlist excerpt (pin names and nets, part order shuffled) for the footprints in the layout excerpt that follows; sources: Cadence DE-HDL packaged netlist, KiCad conversion of 03242023_DA0F0TMBIJ0_F0T_Motherboard_J_brd_V01_OCP.brd

PC1359  Q_CAP  0.1UF 25V 10% X7R  pkg 0402  page 286 : A = GND ; B = PVCCIN_CPU1_VREF
R3714  Q_RES  0 5% CHIP  pkg 0402LF  page 233 : A = SMB_VR_3V3AUX_SDA_R6 ; B = SMB_VR_3V3AUX_SDA

(kicad_pcb
	(version 20260206)
	(generator "pcbnew")
	(generator_version "10.0")
	(general
		(thickness 1.6)
		(legacy_teardrops no)
	)
	(paper "A4")
	(title_block
		(title "03242023_DA0F0TMBIJ0_F0T_Motherboard_J_brd_V01_OCP.brd")
		(comment 1 "Grand Teton / footprints 883-884 of 6105")
	)
	(layers
		(0 "F.Cu" signal "TOP")
		(4 "In1.Cu" signal "GND")
		(6 "In2.Cu" signal "IN1")
		(8 "In3.Cu" signal "GND1")
		(10 "In4.Cu" signal "IN2")
		(12 "In5.Cu" signal "GND2")
		(14 "In6.Cu" signal "IN3")
		(16 "In7.Cu" signal "GND3")
		(18 "In8.Cu" signal "VCC")
		(20 "In9.Cu" signal "VCC1")
		(22 "In10.Cu" signal "GND4")
		(24 "In11.Cu" signal "IN4")
		(26 "In12.Cu" signal "GND5")
		(28 "In13.Cu" signal "IN5")
		(30 "In14.Cu" signal "GND6")
		(32 "In15.Cu" signal "IN6")
		(34 "In16.Cu" signal "GND7")
		(2 "B.Cu" signal "BOTTOM")
		(9 "F.Adhes" user "F.Adhesive")
		(11 "B.Adhes" user "B.Adhesive")
		(13 "F.Paste" user "Package Geometry/Pastemask Top")
		(15 "B.Paste" user "Package Geometry/Pastemask Bottom")
		(5 "F.SilkS" user "Ref Des/Silkscreen Top")
		(7 "B.SilkS" user "Ref Des/Silkscreen Bottom")
		(1 "F.Mask" user "Board Geometry/Soldermask Top")
		(3 "B.Mask" user "Board Geometry/Soldermask Bottom")
		(17 "Dwgs.User" user "User.Drawings")
		(19 "Cmts.User" user "User.Comments")
		(21 "Eco1.User" user "User.Eco1")
		(23 "Eco2.User" user "User.Eco2")
		(25 "Edge.Cuts" user "Board Geometry/Outline")
		(27 "Margin" user)
		(31 "F.CrtYd" user "Package Geometry/Place Bound Top")
		(29 "B.CrtYd" user "Package Geometry/Place Bound Bottom")
		(35 "F.Fab" user "Ref Des/Assembly Top")
		(33 "B.Fab" user "Ref Des/Assembly Bottom")
	)
	(footprint ""
		(layer "F.Cu")
		(at 54.242716 -113.97869 180)
		(property "Reference" "R3714"
			(at 0 0 180)
			(layer "F.SilkS")
			(hide yes)
			(effects
				(font
					(size 1.27 1.27)
				)
			)
		)
		(property "Value" ""
			(at 0 0 180)
			(layer "F.Fab")
			(effects
				(font
					(size 1.27 1.27)
				)
			)
		)
		(duplicate_pad_numbers_are_jumpers no)
		(fp_line
			(start 0.7874 0.4064)
			(end -0.7874 0.4064)
			(stroke
				(width 0.1524)
				(type default)
			)
			(layer "F.SilkS")
		)
		(fp_line
			(start 0.7874 -0.4064)
			(end 0.7874 0.4064)
			(stroke
				(width 0.1524)
				(type default)
			)
			(layer "F.SilkS")
		)
		(fp_line
			(start -0.7874 0.4064)
			(end -0.7874 -0.4064)
			(stroke
				(width 0.1524)
				(type default)
			)
			(layer "F.SilkS")
		)
		(fp_line
			(start -0.7874 -0.4064)
			(end 0.7874 -0.4064)
			(stroke
				(width 0.1524)
				(type default)
			)
			(layer "F.SilkS")
		)
		(fp_line
			(start 0.67945 0.3048)
			(end 0.120396 0.3048)
			(stroke
				(width 0.1)
				(type default)
			)
			(layer "F.Fab")
		)
		(fp_line
			(start 0.67945 -0.3048)
			(end 0.67945 0.3048)
			(stroke
				(width 0.1)
				(type default)
			)
			(layer "F.Fab")
		)
		(fp_line
			(start 0.12065 -0.2794)
			(end 0.12065 -0.3048)
			(stroke
				(width 0.1)
				(type default)
			)
			(layer "F.Fab")
		)
		(fp_line
			(start 0.12065 -0.3048)
			(end 0.67945 -0.3048)
			(stroke
				(width 0.1)
				(type default)
			)
			(layer "F.Fab")
		)
		(fp_line
			(start 0.120396 0.3048)
			(end 0.120396 0.2794)
			(stroke
				(width 0.1)
				(type default)
			)
			(layer "F.Fab")
		)
		(fp_line
			(start 0.120396 0.2794)
			(end -0.12065 0.2794)
			(stroke
				(width 0.1)
				(type default)
			)
			(layer "F.Fab")
		)
		(fp_line
			(start -0.12065 0.3048)
			(end -0.67945 0.3048)
			(stroke
				(width 0.1)
				(type default)
			)
			(layer "F.Fab")
		)
		(fp_line
			(start -0.12065 0.2794)
			(end -0.12065 0.3048)
			(stroke
				(width 0.1)
				(type default)
			)
			(layer "F.Fab")
		)
		(fp_line
			(start -0.12065 -0.2794)
			(end 0.12065 -0.2794)
			(stroke
				(width 0.1)
				(type default)
			)
			(layer "F.Fab")
		)
		(fp_line
			(start -0.12065 -0.305054)
			(end -0.12065 -0.2794)
			(stroke
				(width 0.1)
				(type default)
			)
			(layer "F.Fab")
		)
		(fp_line
			(start -0.67945 0.3048)
			(end -0.67945 -0.305054)
			(stroke
				(width 0.1)
				(type default)
			)
			(layer "F.Fab")
		)
		(fp_line
			(start -0.67945 -0.305054)
			(end -0.12065 -0.305054)
			(stroke
				(width 0.1)
				(type default)
			)
			(layer "F.Fab")
		)
		(pad "1" smd circle
			(at -0.40005 0 180)
			(size 0 0)
			(layers "F.Cu" "F.Mask" "F.Paste")
			(net "SMB_VR_3V3AUX_SDA_R6")
		)
		(pad "2" smd circle
			(at 0.40005 0 180)
			(size 0 0)
			(layers "F.Cu" "F.Mask" "F.Paste")
			(net "SMB_VR_3V3AUX_SDA")
		)
	)
	(footprint ""
		(layer "F.Cu")
		(at 110.485682 -338.298028 -90)
		(property "Reference" "PC1359"
			(at 0 0 270)
			(layer "F.SilkS")
			(hide yes)
			(effects
				(font
					(size 1.27 1.27)
				)
			)
		)
		(property "Value" ""
			(at 0 0 270)
			(layer "F.Fab")
			(effects
				(font
					(size 1.27 1.27)
				)
			)
		)
		(duplicate_pad_numbers_are_jumpers no)
		(fp_line
			(start -0.7874 0.4064)
			(end -0.7874 -0.4064)
			(stroke
				(width 0.1524)
				(type default)
			)
			(layer "F.SilkS")
		)
		(fp_line
			(start 0.7874 0.4064)
			(end -0.7874 0.4064)
			(stroke
				(width 0.1524)
				(type default)
			)
			(layer "F.SilkS")
		)
		(fp_line
			(start -0.7874 -0.4064)
			(end 0.7874 -0.4064)
			(stroke
				(width 0.1524)
				(type default)
			)
			(layer "F.SilkS")
		)
		(fp_line
			(start 0.7874 -0.4064)
			(end 0.7874 0.4064)
			(stroke
				(width 0.1524)
				(type default)
			)
			(layer "F.SilkS")
		)
		(fp_line
			(start -0.67945 0.3048)
			(end -0.67945 -0.305054)
			(stroke
				(width 0.1)
				(type default)
			)
			(layer "F.Fab")
		)
		(fp_line
			(start -0.12065 0.3048)
			(end -0.67945 0.3048)
			(stroke
				(width 0.1)
				(type default)
			)
			(layer "F.Fab")
		)
		(fp_line
			(start 0.120396 0.3048)
			(end 0.120396 0.2794)
			(stroke
				(width 0.1)
				(type default)
			)
			(layer "F.Fab")
		)
		(fp_line
			(start 0.67945 0.3048)
			(end 0.120396 0.3048)
			(stroke
				(width 0.1)
				(type default)
			)
			(layer "F.Fab")
		)
		(fp_line
			(start -0.12065 0.2794)
			(end -0.12065 0.3048)
			(stroke
				(width 0.1)
				(type default)
			)
			(layer "F.Fab")
		)
		(fp_line
			(start 0.120396 0.2794)
			(end -0.12065 0.2794)
			(stroke
				(width 0.1)
				(type default)
			)
			(layer "F.Fab")
		)
		(fp_line
			(start -0.12065 -0.2794)
			(end 0.12065 -0.2794)
			(stroke
				(width 0.1)
				(type default)
			)
			(layer "F.Fab")
		)
		(fp_line
			(start 0.12065 -0.2794)
			(end 0.12065 -0.3048)
			(stroke
				(width 0.1)
				(type default)
			)
			(layer "F.Fab")
		)
		(fp_line
			(start 0.12065 -0.3048)
			(end 0.67945 -0.3048)
			(stroke
				(width 0.1)
				(type default)
			)
			(layer "F.Fab")
		)
		(fp_line
			(start 0.67945 -0.3048)
			(end 0.67945 0.3048)
			(stroke
				(width 0.1)
				(type default)
			)
			(layer "F.Fab")
		)
		(fp_line
			(start -0.67945 -0.305054)
			(end -0.12065 -0.305054)
			(stroke
				(width 0.1)
				(type default)
			)
			(layer "F.Fab")
		)
		(fp_line
			(start -0.12065 -0.305054)
			(end -0.12065 -0.2794)
			(stroke
				(width 0.1)
				(type default)
			)
			(layer "F.Fab")
		)
		(pad "1" smd circle
			(at -0.40005 0 270)
			(size 0 0)
			(layers "F.Cu" "F.Mask" "F.Paste")
			(net "GND")
		)
		(pad "2" smd circle
			(at 0.40005 0 270)
			(size 0 0)
			(layers "F.Cu" "F.Mask" "F.Paste")
			(net "PVCCIN_CPU1_VREF")
		)
	)
)
